# S9S_MB_2U (Grand Teton) — schematic netlist excerpt (pin names and nets, part order shuffled) for the footprints in the layout excerpt that follows; sources: Cadence DE-HDL packaged netlist, KiCad conversion of 03242023_DA0F0TMBIJ0_F0T_Motherboard_J_brd_V01_OCP.brd

R2573  Q_RES  1K 1% CHIP  pkg 0402LF  page 292 : A = P3V3_AUX ; B = IRQ_PVCCFA_CPU1_VRHOT_R_N
PR3781  Q_RES  845 1% EMPTY  pkg 0402LF  page 156 : A = P12V_OCP_SENSE_1 ; B = GND

(kicad_pcb
	(version 20260206)
	(generator "pcbnew")
	(generator_version "10.0")
	(general
		(thickness 1.6)
		(legacy_teardrops no)
	)
	(paper "A4")
	(title_block
		(title "03242023_DA0F0TMBIJ0_F0T_Motherboard_J_brd_V01_OCP.brd")
		(comment 1 "Grand Teton / footprints 2345-2346 of 6105")
	)
	(layers
		(0 "F.Cu" signal "TOP")
		(4 "In1.Cu" signal "GND")
		(6 "In2.Cu" signal "IN1")
		(8 "In3.Cu" signal "GND1")
		(10 "In4.Cu" signal "IN2")
		(12 "In5.Cu" signal "GND2")
		(14 "In6.Cu" signal "IN3")
		(16 "In7.Cu" signal "GND3")
		(18 "In8.Cu" signal "VCC")
		(20 "In9.Cu" signal "VCC1")
		(22 "In10.Cu" signal "GND4")
		(24 "In11.Cu" signal "IN4")
		(26 "In12.Cu" signal "GND5")
		(28 "In13.Cu" signal "IN5")
		(30 "In14.Cu" signal "GND6")
		(32 "In15.Cu" signal "IN6")
		(34 "In16.Cu" signal "GND7")
		(2 "B.Cu" signal "BOTTOM")
		(9 "F.Adhes" user "F.Adhesive")
		(11 "B.Adhes" user "B.Adhesive")
		(13 "F.Paste" user "Package Geometry/Pastemask Top")
		(15 "B.Paste" user "Package Geometry/Pastemask Bottom")
		(5 "F.SilkS" user "Ref Des/Silkscreen Top")
		(7 "B.SilkS" user "Ref Des/Silkscreen Bottom")
		(1 "F.Mask" user "Board Geometry/Soldermask Top")
		(3 "B.Mask" user "Board Geometry/Soldermask Bottom")
		(17 "Dwgs.User" user "User.Drawings")
		(19 "Cmts.User" user "User.Comments")
		(21 "Eco1.User" user "User.Eco1")
		(23 "Eco2.User" user "User.Eco2")
		(25 "Edge.Cuts" user "Board Geometry/Outline")
		(27 "Margin" user)
		(31 "F.CrtYd" user "Package Geometry/Place Bound Top")
		(29 "B.CrtYd" user "Package Geometry/Place Bound Bottom")
		(35 "F.Fab" user "Ref Des/Assembly Top")
		(33 "B.Fab" user "Ref Des/Assembly Bottom")
	)
	(footprint ""
		(layer "F.Cu")
		(at 38.72738 -128.108202 -90)
		(property "Reference" "R2573"
			(at 0 0 270)
			(layer "F.SilkS")
			(hide yes)
			(effects
				(font
					(size 1.27 1.27)
				)
			)
		)
		(property "Value" ""
			(at 0 0 270)
			(layer "F.Fab")
			(effects
				(font
					(size 1.27 1.27)
				)
			)
		)
		(duplicate_pad_numbers_are_jumpers no)
		(fp_line
			(start -0.7874 0.4064)
			(end -0.7874 -0.4064)
			(stroke
				(width 0.1524)
				(type default)
			)
			(layer "F.SilkS")
		)
		(fp_line
			(start 0.7874 0.4064)
			(end -0.7874 0.4064)
			(stroke
				(width 0.1524)
				(type default)
			)
			(layer "F.SilkS")
		)
		(fp_line
			(start -0.7874 -0.4064)
			(end 0.7874 -0.4064)
			(stroke
				(width 0.1524)
				(type default)
			)
			(layer "F.SilkS")
		)
		(fp_line
			(start 0.7874 -0.4064)
			(end 0.7874 0.4064)
			(stroke
				(width 0.1524)
				(type default)
			)
			(layer "F.SilkS")
		)
		(fp_line
			(start -0.67945 0.3048)
			(end -0.67945 -0.305054)
			(stroke
				(width 0.1)
				(type default)
			)
			(layer "F.Fab")
		)
		(fp_line
			(start -0.12065 0.3048)
			(end -0.67945 0.3048)
			(stroke
				(width 0.1)
				(type default)
			)
			(layer "F.Fab")
		)
		(fp_line
			(start 0.120396 0.3048)
			(end 0.120396 0.2794)
			(stroke
				(width 0.1)
				(type default)
			)
			(layer "F.Fab")
		)
		(fp_line
			(start 0.67945 0.3048)
			(end 0.120396 0.3048)
			(stroke
				(width 0.1)
				(type default)
			)
			(layer "F.Fab")
		)
		(fp_line
			(start -0.12065 0.2794)
			(end -0.12065 0.3048)
			(stroke
				(width 0.1)
				(type default)
			)
			(layer "F.Fab")
		)
		(fp_line
			(start 0.120396 0.2794)
			(end -0.12065 0.2794)
			(stroke
				(width 0.1)
				(type default)
			)
			(layer "F.Fab")
		)
		(fp_line
			(start -0.12065 -0.2794)
			(end 0.12065 -0.2794)
			(stroke
				(width 0.1)
				(type default)
			)
			(layer "F.Fab")
		)
		(fp_line
			(start 0.12065 -0.2794)
			(end 0.12065 -0.3048)
			(stroke
				(width 0.1)
				(type default)
			)
			(layer "F.Fab")
		)
		(fp_line
			(start 0.12065 -0.3048)
			(end 0.67945 -0.3048)
			(stroke
				(width 0.1)
				(type default)
			)
			(layer "F.Fab")
		)
		(fp_line
			(start 0.67945 -0.3048)
			(end 0.67945 0.3048)
			(stroke
				(width 0.1)
				(type default)
			)
			(layer "F.Fab")
		)
		(fp_line
			(start -0.67945 -0.305054)
			(end -0.12065 -0.305054)
			(stroke
				(width 0.1)
				(type default)
			)
			(layer "F.Fab")
		)
		(fp_line
			(start -0.12065 -0.305054)
			(end -0.12065 -0.2794)
			(stroke
				(width 0.1)
				(type default)
			)
			(layer "F.Fab")
		)
		(pad "1" smd circle
			(at -0.40005 0 270)
			(size 0 0)
			(layers "F.Cu" "F.Mask" "F.Paste")
			(net "P3V3_AUX")
		)
		(pad "2" smd circle
			(at 0.40005 0 270)
			(size 0 0)
			(layers "F.Cu" "F.Mask" "F.Paste")
			(net "IRQ_PVCCFA_CPU1_VRHOT_R_N")
		)
	)
	(footprint ""
		(layer "F.Cu")
		(at 447.687192 -22.125178 180)
		(property "Reference" "PR3781"
			(at 0 0 180)
			(layer "F.SilkS")
			(hide yes)
			(effects
				(font
					(size 1.27 1.27)
				)
			)
		)
		(property "Value" ""
			(at 0 0 180)
			(layer "F.Fab")
			(effects
				(font
					(size 1.27 1.27)
				)
			)
		)
		(duplicate_pad_numbers_are_jumpers no)
		(fp_line
			(start 0.7874 0.4064)
			(end -0.7874 0.4064)
			(stroke
				(width 0.1524)
				(type default)
			)
			(layer "F.SilkS")
		)
		(fp_line
			(start 0.7874 -0.4064)
			(end 0.7874 0.4064)
			(stroke
				(width 0.1524)
				(type default)
			)
			(layer "F.SilkS")
		)
		(fp_line
			(start -0.7874 0.4064)
			(end -0.7874 -0.4064)
			(stroke
				(width 0.1524)
				(type default)
			)
			(layer "F.SilkS")
		)
		(fp_line
			(start -0.7874 -0.4064)
			(end 0.7874 -0.4064)
			(stroke
				(width 0.1524)
				(type default)
			)
			(layer "F.SilkS")
		)
		(fp_line
			(start 0.67945 0.3048)
			(end 0.120396 0.3048)
			(stroke
				(width 0.1)
				(type default)
			)
			(layer "F.Fab")
		)
		(fp_line
			(start 0.67945 -0.3048)
			(end 0.67945 0.3048)
			(stroke
				(width 0.1)
				(type default)
			)
			(layer "F.Fab")
		)
		(fp_line
			(start 0.12065 -0.2794)
			(end 0.12065 -0.3048)
			(stroke
				(width 0.1)
				(type default)
			)
			(layer "F.Fab")
		)
		(fp_line
			(start 0.12065 -0.3048)
			(end 0.67945 -0.3048)
			(stroke
				(width 0.1)
				(type default)
			)
			(layer "F.Fab")
		)
		(fp_line
			(start 0.120396 0.3048)
			(end 0.120396 0.2794)
			(stroke
				(width 0.1)
				(type default)
			)
			(layer "F.Fab")
		)
		(fp_line
			(start 0.120396 0.2794)
			(end -0.12065 0.2794)
			(stroke
				(width 0.1)
				(type default)
			)
			(layer "F.Fab")
		)
		(fp_line
			(start -0.12065 0.3048)
			(end -0.67945 0.3048)
			(stroke
				(width 0.1)
				(type default)
			)
			(layer "F.Fab")
		)
		(fp_line
			(start -0.12065 0.2794)
			(end -0.12065 0.3048)
			(stroke
				(width 0.1)
				(type default)
			)
			(layer "F.Fab")
		)
		(fp_line
			(start -0.12065 -0.2794)
			(end 0.12065 -0.2794)
			(stroke
				(width 0.1)
				(type default)
			)
			(layer "F.Fab")
		)
		(fp_line
			(start -0.12065 -0.305054)
			(end -0.12065 -0.2794)
			(stroke
				(width 0.1)
				(type default)
			)
			(layer "F.Fab")
		)
		(fp_line
			(start -0.67945 0.3048)
			(end -0.67945 -0.305054)
			(stroke
				(width 0.1)
				(type default)
			)
			(layer "F.Fab")
		)
		(fp_line
			(start -0.67945 -0.305054)
			(end -0.12065 -0.305054)
			(stroke
				(width 0.1)
				(type default)
			)
			(layer "F.Fab")
		)
		(pad "1" smd circle
			(at -0.40005 0 180)
			(size 0 0)
			(layers "F.Cu" "F.Mask" "F.Paste")
			(net "P12V_OCP_SENSE_1")
		)
		(pad "2" smd circle
			(at 0.40005 0 180)
			(size 0 0)
			(layers "F.Cu" "F.Mask" "F.Paste")
			(net "GND")
		)
	)
)
